# T6G (Grand Teton) — schematic netlist excerpt (pin names and nets, part order shuffled) for the footprints in the layout excerpt that follows; sources: Cadence DE-HDL packaged netlist, KiCad conversion of 04192023_DAF0TMB3IC0_F0TG_MB_C_brd_V02_OCP.brd

PC2173  Q_CAP  10UF 16V 10% X6S  pkg C0805  page 141 : A = P3V3_OCP_V3_2_R ; B = GND
R4602  Q_RES  0 5% CHIP  pkg 0402LF  page 139 : A = CLK_50M_NCSI_OCP_V3_2_ISO ; B = CLK_50M_NCSI_OCP_V3_2_ISO_R
R5007  Q_RES  1K 1% EMPTY  pkg 0402LF  page 159 : A = PVDD11_S3_P0 ; B = I3C_SPD_DDRAF_CPU0_LVC1_SDA

(kicad_pcb
	(version 20260206)
	(generator "pcbnew")
	(generator_version "10.0")
	(general
		(thickness 1.6)
		(legacy_teardrops no)
	)
	(paper "A4")
	(title_block
		(title "04192023_DAF0TMB3IC0_F0TG_MB_C_brd_V02_OCP.brd")
		(comment 1 "Grand Teton / footprints 4672-4674 of 8354")
	)
	(layers
		(0 "F.Cu" signal "TOP")
		(4 "In1.Cu" signal "GND")
		(6 "In2.Cu" signal "IN1")
		(8 "In3.Cu" signal "GND1")
		(10 "In4.Cu" signal "IN2")
		(12 "In5.Cu" signal "GND2")
		(14 "In6.Cu" signal "IN3")
		(16 "In7.Cu" signal "GND3")
		(18 "In8.Cu" signal "VCC")
		(20 "In9.Cu" signal "VCC1")
		(22 "In10.Cu" signal "GND4")
		(24 "In11.Cu" signal "IN4")
		(26 "In12.Cu" signal "GND5")
		(28 "In13.Cu" signal "IN5")
		(30 "In14.Cu" signal "GND6")
		(32 "In15.Cu" signal "IN6")
		(34 "In16.Cu" signal "GND7")
		(2 "B.Cu" signal "BOTTOM")
		(9 "F.Adhes" user "F.Adhesive")
		(11 "B.Adhes" user "B.Adhesive")
		(13 "F.Paste" user "Package Geometry/Pastemask Top")
		(15 "B.Paste" user "Package Geometry/Pastemask Bottom")
		(5 "F.SilkS" user "Ref Des/Silkscreen Top")
		(7 "B.SilkS" user "Ref Des/Silkscreen Bottom")
		(1 "F.Mask" user "Board Geometry/Soldermask Top")
		(3 "B.Mask" user "Board Geometry/Soldermask Bottom")
		(17 "Dwgs.User" user "User.Drawings")
		(19 "Cmts.User" user "User.Comments")
		(21 "Eco1.User" user "User.Eco1")
		(23 "Eco2.User" user "User.Eco2")
		(25 "Edge.Cuts" user "Board Geometry/Outline")
		(27 "Margin" user)
		(31 "F.CrtYd" user "Package Geometry/Place Bound Top")
		(29 "B.CrtYd" user "Package Geometry/Place Bound Bottom")
		(35 "F.Fab" user "Ref Des/Assembly Top")
		(33 "B.Fab" user "Ref Des/Assembly Bottom")
	)
	(footprint ""
		(layer "F.Cu")
		(at 86.311994 -31.667958 90)
		(property "Reference" "R4602"
			(at 0 0 90)
			(layer "F.SilkS")
			(hide yes)
			(effects
				(font
					(size 1.27 1.27)
				)
			)
		)
		(property "Value" ""
			(at 0 0 90)
			(layer "F.Fab")
			(effects
				(font
					(size 1.27 1.27)
				)
			)
		)
		(duplicate_pad_numbers_are_jumpers no)
		(fp_line
			(start 0.7874 -0.4064)
			(end 0.7874 0.4064)
			(stroke
				(width 0.1524)
				(type default)
			)
			(layer "F.SilkS")
		)
		(fp_line
			(start -0.7874 -0.4064)
			(end 0.7874 -0.4064)
			(stroke
				(width 0.1524)
				(type default)
			)
			(layer "F.SilkS")
		)
		(fp_line
			(start 0.7874 0.4064)
			(end -0.7874 0.4064)
			(stroke
				(width 0.1524)
				(type default)
			)
			(layer "F.SilkS")
		)
		(fp_line
			(start -0.7874 0.4064)
			(end -0.7874 -0.4064)
			(stroke
				(width 0.1524)
				(type default)
			)
			(layer "F.SilkS")
		)
		(fp_line
			(start -0.12065 -0.305054)
			(end -0.12065 -0.2794)
			(stroke
				(width 0.1)
				(type default)
			)
			(layer "F.Fab")
		)
		(fp_line
			(start -0.67945 -0.305054)
			(end -0.12065 -0.305054)
			(stroke
				(width 0.1)
				(type default)
			)
			(layer "F.Fab")
		)
		(fp_line
			(start 0.67945 -0.3048)
			(end 0.67945 0.3048)
			(stroke
				(width 0.1)
				(type default)
			)
			(layer "F.Fab")
		)
		(fp_line
			(start 0.12065 -0.3048)
			(end 0.67945 -0.3048)
			(stroke
				(width 0.1)
				(type default)
			)
			(layer "F.Fab")
		)
		(fp_line
			(start 0.12065 -0.2794)
			(end 0.12065 -0.3048)
			(stroke
				(width 0.1)
				(type default)
			)
			(layer "F.Fab")
		)
		(fp_line
			(start -0.12065 -0.2794)
			(end 0.12065 -0.2794)
			(stroke
				(width 0.1)
				(type default)
			)
			(layer "F.Fab")
		)
		(fp_line
			(start 0.120396 0.2794)
			(end -0.12065 0.2794)
			(stroke
				(width 0.1)
				(type default)
			)
			(layer "F.Fab")
		)
		(fp_line
			(start -0.12065 0.2794)
			(end -0.12065 0.3048)
			(stroke
				(width 0.1)
				(type default)
			)
			(layer "F.Fab")
		)
		(fp_line
			(start 0.67945 0.3048)
			(end 0.120396 0.3048)
			(stroke
				(width 0.1)
				(type default)
			)
			(layer "F.Fab")
		)
		(fp_line
			(start 0.120396 0.3048)
			(end 0.120396 0.2794)
			(stroke
				(width 0.1)
				(type default)
			)
			(layer "F.Fab")
		)
		(fp_line
			(start -0.12065 0.3048)
			(end -0.67945 0.3048)
			(stroke
				(width 0.1)
				(type default)
			)
			(layer "F.Fab")
		)
		(fp_line
			(start -0.67945 0.3048)
			(end -0.67945 -0.305054)
			(stroke
				(width 0.1)
				(type default)
			)
			(layer "F.Fab")
		)
		(pad "1" smd circle
			(at -0.40005 0 90)
			(size 0 0)
			(layers "F.Cu" "F.Mask" "F.Paste")
			(net "CLK_50M_NCSI_OCP_V3_2_ISO")
		)
		(pad "2" smd circle
			(at 0.40005 0 90)
			(size 0 0)
			(layers "F.Cu" "F.Mask" "F.Paste")
			(net "CLK_50M_NCSI_OCP_V3_2_ISO_R")
		)
	)
	(footprint ""
		(layer "F.Cu")
		(at 297.330368 -148.493988)
		(property "Reference" "R5007"
			(at 0 0 0)
			(layer "F.SilkS")
			(hide yes)
			(effects
				(font
					(size 1.27 1.27)
				)
			)
		)
		(property "Value" ""
			(at 0 0 0)
			(layer "F.Fab")
			(effects
				(font
					(size 1.27 1.27)
				)
			)
		)
		(duplicate_pad_numbers_are_jumpers no)
		(fp_line
			(start -0.7874 -0.4064)
			(end 0.7874 -0.4064)
			(stroke
				(width 0.1524)
				(type default)
			)
			(layer "F.SilkS")
		)
		(fp_line
			(start -0.7874 0.4064)
			(end -0.7874 -0.4064)
			(stroke
				(width 0.1524)
				(type default)
			)
			(layer "F.SilkS")
		)
		(fp_line
			(start 0.7874 -0.4064)
			(end 0.7874 0.4064)
			(stroke
				(width 0.1524)
				(type default)
			)
			(layer "F.SilkS")
		)
		(fp_line
			(start 0.7874 0.4064)
			(end -0.7874 0.4064)
			(stroke
				(width 0.1524)
				(type default)
			)
			(layer "F.SilkS")
		)
		(fp_line
			(start -0.67945 -0.305054)
			(end -0.12065 -0.305054)
			(stroke
				(width 0.1)
				(type default)
			)
			(layer "F.Fab")
		)
		(fp_line
			(start -0.67945 0.3048)
			(end -0.67945 -0.305054)
			(stroke
				(width 0.1)
				(type default)
			)
			(layer "F.Fab")
		)
		(fp_line
			(start -0.12065 -0.305054)
			(end -0.12065 -0.2794)
			(stroke
				(width 0.1)
				(type default)
			)
			(layer "F.Fab")
		)
		(fp_line
			(start -0.12065 -0.2794)
			(end 0.12065 -0.2794)
			(stroke
				(width 0.1)
				(type default)
			)
			(layer "F.Fab")
		)
		(fp_line
			(start -0.12065 0.2794)
			(end -0.12065 0.3048)
			(stroke
				(width 0.1)
				(type default)
			)
			(layer "F.Fab")
		)
		(fp_line
			(start -0.12065 0.3048)
			(end -0.67945 0.3048)
			(stroke
				(width 0.1)
				(type default)
			)
			(layer "F.Fab")
		)
		(fp_line
			(start 0.120396 0.2794)
			(end -0.12065 0.2794)
			(stroke
				(width 0.1)
				(type default)
			)
			(layer "F.Fab")
		)
		(fp_line
			(start 0.120396 0.3048)
			(end 0.120396 0.2794)
			(stroke
				(width 0.1)
				(type default)
			)
			(layer "F.Fab")
		)
		(fp_line
			(start 0.12065 -0.3048)
			(end 0.67945 -0.3048)
			(stroke
				(width 0.1)
				(type default)
			)
			(layer "F.Fab")
		)
		(fp_line
			(start 0.12065 -0.2794)
			(end 0.12065 -0.3048)
			(stroke
				(width 0.1)
				(type default)
			)
			(layer "F.Fab")
		)
		(fp_line
			(start 0.67945 -0.3048)
			(end 0.67945 0.3048)
			(stroke
				(width 0.1)
				(type default)
			)
			(layer "F.Fab")
		)
		(fp_line
			(start 0.67945 0.3048)
			(end 0.120396 0.3048)
			(stroke
				(width 0.1)
				(type default)
			)
			(layer "F.Fab")
		)
		(pad "1" smd circle
			(at -0.40005 0)
			(size 0 0)
			(layers "F.Cu" "F.Mask" "F.Paste")
			(net "PVDD11_S3_P0")
		)
		(pad "2" smd circle
			(at 0.40005 0)
			(size 0 0)
			(layers "F.Cu" "F.Mask" "F.Paste")
			(net "I3C_SPD_DDRAF_CPU0_LVC1_SDA")
		)
	)
	(footprint ""
		(layer "F.Cu")
		(at 92.178632 -69.84238 180)
		(property "Reference" "PC2173"
			(at 0 0 180)
			(layer "F.SilkS")
			(hide yes)
			(effects
				(font
					(size 1.27 1.27)
				)
			)
		)
		(property "Value" ""
			(at 0 0 180)
			(layer "F.Fab")
			(effects
				(font
					(size 1.27 1.27)
				)
			)
		)
		(duplicate_pad_numbers_are_jumpers no)
		(fp_line
			(start 1.524 0.762)
			(end -1.524 0.762)
			(stroke
				(width 0.1524)
				(type default)
			)
			(layer "F.SilkS")
		)
		(fp_line
			(start 1.524 -0.762)
			(end 1.524 0.762)
			(stroke
				(width 0.1524)
				(type default)
			)
			(layer "F.SilkS")
		)
		(fp_line
			(start -1.524 0.762)
			(end -1.524 -0.762)
			(stroke
				(width 0.1524)
				(type default)
			)
			(layer "F.SilkS")
		)
		(fp_line
			(start -1.524 -0.762)
			(end 1.524 -0.762)
			(stroke
				(width 0.1524)
				(type default)
			)
			(layer "F.SilkS")
		)
		(fp_line
			(start 1.1049 0.724916)
			(end 1.1049 -0.724916)
			(stroke
				(width 0.1)
				(type default)
			)
			(layer "F.Fab")
		)
		(fp_line
			(start 1.1049 -0.724916)
			(end -1.1049 -0.724916)
			(stroke
				(width 0.1)
				(type default)
			)
			(layer "F.Fab")
		)
		(fp_line
			(start -1.1049 0.724916)
			(end 1.1049 0.724916)
			(stroke
				(width 0.1)
				(type default)
			)
			(layer "F.Fab")
		)
		(fp_line
			(start -1.1049 -0.724916)
			(end -1.1049 0.724916)
			(stroke
				(width 0.1)
				(type default)
			)
			(layer "F.Fab")
		)
		(pad "1" smd rect
			(at -0.889 0)
			(size 1.016 1.27)
			(layers "F.Cu" "F.Mask" "F.Paste")
			(net "P3V3_OCP_V3_2_R")
		)
		(pad "2" smd rect
			(at 0.889 0)
			(size 1.016 1.27)
			(layers "F.Cu" "F.Mask" "F.Paste")
			(net "GND")
		)
	)
)
